# BASEBOARD_FAB2 (Tioga Pass) — schematic netlist excerpt (pin names and nets, part order shuffled) for the footprints in the layout excerpt that follows; sources: Cadence DE-HDL packaged netlist, KiCad conversion of Wiwynn_Tioga_Pass_MB.brd

C7A38  CAP_A  0.1UF 16V 10% X7R  pkg 0402V  page 218 : A = VR_PVDDQ_DEF_VDD ; B = GND

U3B1  PCA9617  IC  pkg SSOP  page 99
  VCCA  = PVCCIO_CPU1
  SCLA  = SMB_DDR_KLM_SCL_G
  SDAA  = SMB_DDR_KLM_SDA_G
  EN  = TP_SMB_DDR_KLM_EN
  SDAB  = SMB_DDR_KLM_VPP_SDA_R
  SCLB  = SMB_DDR_KLM_VPP_SCL_R
  VCCB  = PVPP_KLM

C4G10  CAP  2200PF 50V 10% X7R  pkg 0402LF  page 233 : A = VR_COMP_RC_PVPP_GHJ ; B = VR_COMP_PVPP_GHJ_3

(kicad_pcb
	(version 20260206)
	(generator "pcbnew")
	(generator_version "10.0")
	(general
		(thickness 1.6)
		(legacy_teardrops no)
	)
	(paper "A4")
	(title_block
		(title "Wiwynn_Tioga_Pass_MB.brd")
		(comment 1 "Tioga Pass / footprints 572-574 of 4770")
	)
	(layers
		(0 "F.Cu" signal "TOP")
		(4 "In1.Cu" signal "L2GND")
		(6 "In2.Cu" signal "L3")
		(8 "In3.Cu" signal "L4GND")
		(10 "In4.Cu" signal "L5")
		(12 "In5.Cu" signal "L6GND")
		(14 "In6.Cu" signal "L7VCC")
		(16 "In7.Cu" signal "L8VCC")
		(18 "In8.Cu" signal "L9GND")
		(20 "In9.Cu" signal "L10")
		(22 "In10.Cu" signal "L11GND")
		(24 "In11.Cu" signal "L12")
		(26 "In12.Cu" signal "L13GND")
		(2 "B.Cu" signal "BOTTOM")
		(9 "F.Adhes" user "F.Adhesive")
		(11 "B.Adhes" user "B.Adhesive")
		(13 "F.Paste" user "Package Geometry/Pastemask Top")
		(15 "B.Paste" user "Package Geometry/Pastemask Bottom")
		(5 "F.SilkS" user "Ref Des/Silkscreen Top")
		(7 "B.SilkS" user "Ref Des/Silkscreen Bottom")
		(1 "F.Mask" user "Board Geometry/Soldermask Top")
		(3 "B.Mask" user "Board Geometry/Soldermask Bottom")
		(17 "Dwgs.User" user "User.Drawings")
		(19 "Cmts.User" user "User.Comments")
		(21 "Eco1.User" user "User.Eco1")
		(23 "Eco2.User" user "User.Eco2")
		(25 "Edge.Cuts" user "Board Geometry/Outline")
		(27 "Margin" user)
		(31 "F.CrtYd" user "Package Geometry/Place Bound Top")
		(29 "B.CrtYd" user "Package Geometry/Place Bound Bottom")
		(35 "F.Fab" user "Ref Des/Assembly Top")
		(33 "B.Fab" user "Ref Des/Assembly Bottom")
	)
	(footprint ""
		(layer "F.Cu")
		(at 355.24948 -135.742934)
		(property "Reference" "C7A38"
			(at 0 0 0)
			(layer "F.SilkS")
			(hide yes)
			(effects
				(font
					(size 1.27 1.27)
				)
			)
		)
		(property "Value" ""
			(at 0 0 0)
			(layer "F.Fab")
			(effects
				(font
					(size 1.27 1.27)
				)
			)
		)
		(duplicate_pad_numbers_are_jumpers no)
		(fp_rect
			(start -0.3048 0.9906)
			(end 0.3048 -0.1016)
			(stroke
				(width 0)
				(type default)
			)
			(fill no)
			(layer "F.CrtYd")
		)
		(fp_line
			(start -0.3048 -0.1016)
			(end -0.3048 0.9906)
			(stroke
				(width 0.1)
				(type default)
			)
			(layer "F.Fab")
		)
		(fp_line
			(start -0.3048 0.9906)
			(end 0.3048 0.9906)
			(stroke
				(width 0.1)
				(type default)
			)
			(layer "F.Fab")
		)
		(fp_line
			(start 0.3048 -0.1016)
			(end -0.3048 -0.1016)
			(stroke
				(width 0.1)
				(type default)
			)
			(layer "F.Fab")
		)
		(fp_line
			(start 0.3048 0.9906)
			(end 0.3048 -0.1016)
			(stroke
				(width 0.1)
				(type default)
			)
			(layer "F.Fab")
		)
		(pad "1" smd rect
			(at 0 0)
			(size 0.508 0.508)
			(layers "F.Cu" "F.Mask" "F.Paste")
			(net "VR_PVDDQ_DEF_VDD")
		)
		(pad "2" smd rect
			(at 0 0.889)
			(size 0.508 0.508)
			(layers "F.Cu" "F.Mask" "F.Paste")
			(net "GND")
		)
		(zone
			(layer "F.Cu")
			(hatch none 0.5)
			(connect_pads
				(clearance 0)
			)
			(min_thickness 0.25)
			(keepout
				(tracks not_allowed)
				(vias allowed)
				(pads allowed)
				(copperpour not_allowed)
				(footprints allowed)
			)
			(placement
				(enabled no)
				(sheetname "")
			)
			(fill
				(thermal_gap 0.5)
				(thermal_bridge_width 0.5)
				(island_removal_mode 0)
			)
			(polygon
				(pts
					(xy 354.99548 -135.107934) (xy 355.50348 -135.107934) (xy 355.50348 -135.488934) (xy 354.99548 -135.488934)
				)
			)
		)
		(zone
			(layer "F.Cu")
			(hatch none 0.5)
			(connect_pads
				(clearance 0)
			)
			(min_thickness 0.25)
			(keepout
				(tracks allowed)
				(vias not_allowed)
				(pads allowed)
				(copperpour not_allowed)
				(footprints allowed)
			)
			(placement
				(enabled no)
				(sheetname "")
			)
			(fill
				(thermal_gap 0.5)
				(thermal_bridge_width 0.5)
				(island_removal_mode 0)
			)
			(polygon
				(pts
					(xy 354.99548 -135.107934) (xy 355.50348 -135.107934) (xy 355.50348 -135.488934) (xy 354.99548 -135.488934)
				)
			)
		)
	)
	(footprint ""
		(layer "F.Cu")
		(at 176.0855 -7.874 90)
		(property "Reference" "C4G10"
			(at 0 0 90)
			(layer "F.SilkS")
			(hide yes)
			(effects
				(font
					(size 1.27 1.27)
				)
			)
		)
		(property "Value" ""
			(at 0 0 90)
			(layer "F.Fab")
			(effects
				(font
					(size 1.27 1.27)
				)
			)
		)
		(duplicate_pad_numbers_are_jumpers no)
		(fp_poly
			(pts
				(xy 0.3048 -0.1016) (xy 0.3048 0.9906) (xy -0.3048 0.9906) (xy -0.3048 -0.1016)
			)
			(stroke
				(width 0)
				(type default)
			)
			(fill no)
			(layer "F.CrtYd")
		)
		(fp_line
			(start 0.3048 -0.1016)
			(end -0.3048 -0.1016)
			(stroke
				(width 0.1)
				(type default)
			)
			(layer "F.Fab")
		)
		(fp_line
			(start -0.3048 -0.1016)
			(end -0.3048 0.9906)
			(stroke
				(width 0.1)
				(type default)
			)
			(layer "F.Fab")
		)
		(fp_line
			(start 0.3048 0.9906)
			(end 0.3048 -0.1016)
			(stroke
				(width 0.1)
				(type default)
			)
			(layer "F.Fab")
		)
		(fp_line
			(start -0.3048 0.9906)
			(end 0.3048 0.9906)
			(stroke
				(width 0.1)
				(type default)
			)
			(layer "F.Fab")
		)
		(pad "1" smd rect
			(at 0 0 90)
			(size 0.508 0.508)
			(layers "F.Cu" "F.Mask" "F.Paste")
			(net "VR_COMP_RC_PVPP_GHJ")
		)
		(pad "2" smd rect
			(at 0 0.889 90)
			(size 0.508 0.508)
			(layers "F.Cu" "F.Mask" "F.Paste")
			(net "VR_COMP_PVPP_GHJ_3")
		)
		(zone
			(layer "F.Cu")
			(hatch none 0.5)
			(connect_pads
				(clearance 0)
			)
			(min_thickness 0.25)
			(keepout
				(tracks allowed)
				(vias not_allowed)
				(pads allowed)
				(copperpour not_allowed)
				(footprints allowed)
			)
			(placement
				(enabled no)
				(sheetname "")
			)
			(fill
				(thermal_gap 0.5)
				(thermal_bridge_width 0.5)
				(island_removal_mode 0)
			)
			(polygon
				(pts
					(xy 176.3395 -7.62) (xy 176.3395 -8.128) (xy 176.7205 -8.128) (xy 176.7205 -7.62)
				)
			)
		)
		(zone
			(layer "F.Cu")
			(hatch none 0.5)
			(connect_pads
				(clearance 0)
			)
			(min_thickness 0.25)
			(keepout
				(tracks not_allowed)
				(vias allowed)
				(pads allowed)
				(copperpour not_allowed)
				(footprints allowed)
			)
			(placement
				(enabled no)
				(sheetname "")
			)
			(fill
				(thermal_gap 0.5)
				(thermal_bridge_width 0.5)
				(island_removal_mode 0)
			)
			(polygon
				(pts
					(xy 176.7205 -7.62) (xy 176.7205 -8.128) (xy 176.3395 -8.128) (xy 176.3395 -7.62)
				)
			)
		)
	)
	(footprint ""
		(layer "F.Cu")
		(at 156.70022 -123.7107)
		(property "Reference" "U3B1"
			(at 4.46278 3.54457 0)
			(unlocked yes)
			(layer "F.SilkS")
			(effects
				(font
					(size 0.7874 0.5842)
					(thickness 0.1524)
				)
			)
		)
		(property "Value" ""
			(at 0 0 0)
			(layer "F.Fab")
			(effects
				(font
					(size 1.27 1.27)
				)
			)
		)
		(duplicate_pad_numbers_are_jumpers no)
		(fp_line
			(start 3.225038 2.52476)
			(end 1.348486 2.52476)
			(stroke
				(width 0.1524)
				(type default)
			)
			(layer "F.SilkS")
		)
		(fp_line
			(start 3.225292 -0.57404)
			(end 1.352804 -0.57404)
			(stroke
				(width 0.1524)
				(type default)
			)
			(layer "F.SilkS")
		)
		(fp_circle
			(center -1.454404 -0.556514)
			(end -1.327404 -0.556514)
			(stroke
				(width 0.254)
				(type default)
			)
			(fill no)
			(layer "F.SilkS")
		)
		(fp_poly
			(pts
				(xy 0.7366 -0.57404) (xy 3.8354 -0.57404) (xy 3.8354 2.52476) (xy 0.7366 2.52476)
			)
			(stroke
				(width 0)
				(type default)
			)
			(fill no)
			(layer "F.CrtYd")
		)
		(fp_line
			(start 0.7366 -0.57404)
			(end 3.8354 -0.57404)
			(stroke
				(width 0.1)
				(type default)
			)
			(layer "F.Fab")
		)
		(fp_line
			(start 0.7366 2.52476)
			(end 0.7366 -0.57404)
			(stroke
				(width 0.1)
				(type default)
			)
			(layer "F.Fab")
		)
		(fp_line
			(start 3.8354 -0.57404)
			(end 3.8354 2.52476)
			(stroke
				(width 0.1)
				(type default)
			)
			(layer "F.Fab")
		)
		(fp_line
			(start 3.8354 2.52476)
			(end 0.7366 2.52476)
			(stroke
				(width 0.1)
				(type default)
			)
			(layer "F.Fab")
		)
		(fp_circle
			(center -1.454404 -0.556514)
			(end -1.327404 -0.556514)
			(stroke
				(width 0.254)
				(type default)
			)
			(fill no)
			(layer "F.Fab")
		)
		(pad "1" smd rect
			(at 0 0)
			(size 1.778 0.4572)
			(layers "F.Cu" "F.Mask" "F.Paste")
			(net "PVCCIO_CPU1")
		)
		(pad "2" smd rect
			(at 0 0.65024)
			(size 1.778 0.4572)
			(layers "F.Cu" "F.Mask" "F.Paste")
			(net "SMB_DDR_KLM_SCL_G")
		)
		(pad "3" smd rect
			(at 0 1.30048)
			(size 1.778 0.4572)
			(layers "F.Cu" "F.Mask" "F.Paste")
			(net "SMB_DDR_KLM_SDA_G")
		)
		(pad "4" smd rect
			(at 0 1.95072)
			(size 1.778 0.4572)
			(layers "F.Cu" "F.Mask" "F.Paste")
			(net "GND")
		)
		(pad "5" smd rect
			(at 4.572 1.95072)
			(size 1.778 0.4572)
			(layers "F.Cu" "F.Mask" "F.Paste")
			(net "TP_SMB_DDR_KLM_EN")
		)
		(pad "6" smd rect
			(at 4.572 1.30048)
			(size 1.778 0.4572)
			(layers "F.Cu" "F.Mask" "F.Paste")
			(net "SMB_DDR_KLM_VPP_SDA_R")
		)
		(pad "7" smd rect
			(at 4.572 0.65024)
			(size 1.778 0.4572)
			(layers "F.Cu" "F.Mask" "F.Paste")
			(net "SMB_DDR_KLM_VPP_SCL_R")
		)
		(pad "8" smd rect
			(at 4.572 0)
			(size 1.778 0.4572)
			(layers "F.Cu" "F.Mask" "F.Paste")
			(net "PVPP_KLM")
		)
	)
)
